(kicad_pcb
	(version 20221018)
	(generator pcbnew)
	(general
    (thickness 1.7403)
  )
	(paper "A4")
	(title_block
    (title "Data Center RDIMM DDR4 Tester")
    (date "2024-09-30")
    (rev "1.2.4")
		(comment 9 "footprints 67-76 of 690")
	)
	(layers
    (0 "F.Cu" signal)
    (1 "In1.Cu" power)
    (2 "In2.Cu" signal)
    (3 "In3.Cu" power)
    (4 "In4.Cu" power)
    (5 "In5.Cu" signal)
    (6 "In6.Cu" power)
    (7 "In7.Cu" signal)
    (8 "In8.Cu" power)
    (9 "In9.Cu" signal)
    (10 "In10.Cu" power)
    (31 "B.Cu" signal)
    (32 "B.Adhes" user "B.Adhesive")
    (33 "F.Adhes" user "F.Adhesive")
    (34 "B.Paste" user)
    (35 "F.Paste" user)
    (36 "B.SilkS" user "B.Silkscreen")
    (37 "F.SilkS" user "F.Silkscreen")
    (38 "B.Mask" user)
    (39 "F.Mask" user)
    (40 "Dwgs.User" user "User.Drawings")
    (41 "Cmts.User" user "User.Comments")
    (42 "Eco1.User" user "User.Eco1")
    (43 "Eco2.User" user "User.Eco2")
    (44 "Edge.Cuts" user)
    (45 "Margin" user)
    (46 "B.CrtYd" user "B.Courtyard")
    (47 "F.CrtYd" user "F.Courtyard")
    (48 "B.Fab" user)
    (49 "F.Fab" user)
  )
	(footprint "data-center-rdimm-ddr4-tester-footprints:R_0402_1005Metric" (layer "F.Cu")
    (at 238.434 117.001 180)
    (descr "Resistor SMD 0402")
    (tags "resistor SMD 0402")
    (property "Author" "Antmicro")
    (property "License" "Apache-2.0")
    (property "MPN" "CR0402-FX-4701GLF")
    (property "Manufacturer" "Bourns")
    (property "Sheetfile" "config-spi.kicad_sch")
    (property "Sheetname" "Config SPI flash")
    (property "Tolerance" "1%")
    (property "Val" "4k7")
    (property "ki_description" "4k7 resistor in 0402 package with 1% tolerance")
    (attr smd)
    (fp_text reference "R21" (at -0.786 -0.369 180) (layer "F.SilkS")
        (effects (font (size 0.7 0.7) (thickness 0.15)) (justify left bottom))
    )
    (fp_text value "R_4k7_0402" (at 0 1.4 180) (layer "F.Fab") hide
        (effects (font (size 0.7 0.7) (thickness 0.15)) (justify left bottom))
    )
    (fp_text user "${REFERENCE}" (at -0.95 3.168 180) (layer "F.Fab") hide
        (effects (font (size 0.7 0.7) (thickness 0.15)) (justify left bottom))
    )
    (fp_text user "Author: Antmicro" (at -0.95 4.169 180) (layer "F.Fab") hide
        (effects (font (size 0.7 0.7) (thickness 0.15)) (justify left bottom))
    )
    (fp_text user "License: Apache-2.0" (at -0.95 5.169 180) (layer "F.Fab") hide
        (effects (font (size 0.7 0.7) (thickness 0.15)) (justify left bottom))
    )
    (fp_rect (start -0.93 -0.47) (end 0.93 0.47)
      (stroke (width 0.05) (type solid)) (fill none) (layer "F.CrtYd"))
    (fp_rect (start -0.5 -0.25) (end 0.5 0.25)
      (stroke (width 0.15) (type solid)) (fill none) (layer "F.Fab"))
    (pad "1" smd roundrect (at -0.485 0 180) (size 0.59 0.64) (layers "F.Cu" "F.Paste" "F.Mask") (roundrect_rratio 0.25)
      (net 143 "3V3_SYS") (pintype "passive"))
    (pad "2" smd roundrect (at 0.485 0 180) (size 0.59 0.64) (layers "F.Cu" "F.Paste" "F.Mask") (roundrect_rratio 0.25)
      (net 22 "QSPI_DQ3") (pintype "passive"))
  )
	(footprint "data-center-rdimm-ddr4-tester-footprints:R_0402_1005Metric" (layer "F.Cu")
    (at 222.432 118.271)
    (descr "Resistor SMD 0402")
    (tags "resistor SMD 0402")
    (property "Author" "Antmicro")
    (property "License" "Apache-2.0")
    (property "MPN" "CR0402-FX-4701GLF")
    (property "Manufacturer" "Bourns")
    (property "Sheetfile" "config-spi.kicad_sch")
    (property "Sheetname" "Config SPI flash")
    (property "Tolerance" "1%")
    (property "Val" "4k7")
    (property "ki_description" "4k7 resistor in 0402 package with 1% tolerance")
    (attr smd)
    (fp_text reference "R22" (at -3.062 0.359) (layer "F.SilkS")
        (effects (font (size 0.7 0.7) (thickness 0.15)) (justify left bottom))
    )
    (fp_text value "R_4k7_0402" (at 0 1.4) (layer "F.Fab") hide
        (effects (font (size 0.7 0.7) (thickness 0.15)) (justify left bottom))
    )
    (fp_text user "License: Apache-2.0" (at -0.95 5.169) (layer "F.Fab") hide
        (effects (font (size 0.7 0.7) (thickness 0.15)) (justify left bottom))
    )
    (fp_text user "${REFERENCE}" (at -0.95 3.168) (layer "F.Fab") hide
        (effects (font (size 0.7 0.7) (thickness 0.15)) (justify left bottom))
    )
    (fp_text user "Author: Antmicro" (at -0.95 4.169) (layer "F.Fab") hide
        (effects (font (size 0.7 0.7) (thickness 0.15)) (justify left bottom))
    )
    (fp_rect (start -0.93 -0.47) (end 0.93 0.47)
      (stroke (width 0.05) (type solid)) (fill none) (layer "F.CrtYd"))
    (fp_rect (start -0.5 -0.25) (end 0.5 0.25)
      (stroke (width 0.15) (type solid)) (fill none) (layer "F.Fab"))
    (pad "1" smd roundrect (at -0.485 0) (size 0.59 0.64) (layers "F.Cu" "F.Paste" "F.Mask") (roundrect_rratio 0.25)
      (net 143 "3V3_SYS") (pintype "passive"))
    (pad "2" smd roundrect (at 0.485 0) (size 0.59 0.64) (layers "F.Cu" "F.Paste" "F.Mask") (roundrect_rratio 0.25)
      (net 21 "QSPI_DQ2") (pintype "passive"))
  )
	(footprint "data-center-rdimm-ddr4-tester-footprints:R_0402_1005Metric" (layer "F.Cu")
    (at 224.4005 115.731 180)
    (descr "Resistor SMD 0402")
    (tags "resistor SMD 0402")
    (property "Author" "Antmicro")
    (property "Current" "1A")
    (property "License" "Apache-2.0")
    (property "MPN" "ERJ2GE0R00X")
    (property "Manufacturer" "Panasonic")
    (property "Sheetfile" "config-spi.kicad_sch")
    (property "Sheetname" "Config SPI flash")
    (property "Tolerance" "")
    (property "Val" "0R")
    (property "ki_description" "0R resistor in 0402 package with unspecified tolerance")
    (attr smd)
    (fp_text reference "R23" (at 1.0505 0.401 180) (layer "F.SilkS")
        (effects (font (size 0.7 0.7) (thickness 0.15)) (justify left bottom))
    )
    (fp_text value "R_0R_0402" (at 0 1.4 180) (layer "F.Fab") hide
        (effects (font (size 0.7 0.7) (thickness 0.15)) (justify left bottom))
    )
    (fp_text user "Author: Antmicro" (at -0.95 4.169 180) (layer "F.Fab") hide
        (effects (font (size 0.7 0.7) (thickness 0.15)) (justify left bottom))
    )
    (fp_text user "${REFERENCE}" (at -0.95 3.168 180) (layer "F.Fab") hide
        (effects (font (size 0.7 0.7) (thickness 0.15)) (justify left bottom))
    )
    (fp_text user "License: Apache-2.0" (at -0.95 5.169 180) (layer "F.Fab") hide
        (effects (font (size 0.7 0.7) (thickness 0.15)) (justify left bottom))
    )
    (fp_rect (start -0.93 -0.47) (end 0.93 0.47)
      (stroke (width 0.05) (type solid)) (fill none) (layer "F.CrtYd"))
    (fp_rect (start -0.5 -0.25) (end 0.5 0.25)
      (stroke (width 0.15) (type solid)) (fill none) (layer "F.Fab"))
    (pad "1" smd roundrect (at -0.485 0 180) (size 0.59 0.64) (layers "F.Cu" "F.Paste" "F.Mask") (roundrect_rratio 0.25)
      (net 596 "Net-(U3-~{CS})") (pintype "passive"))
    (pad "2" smd roundrect (at 0.485 0 180) (size 0.59 0.64) (layers "F.Cu" "F.Paste" "F.Mask") (roundrect_rratio 0.25)
      (net 95 "FCS_B") (pintype "passive"))
  )
	(footprint "data-center-rdimm-ddr4-tester-footprints:R_0402_1005Metric" (layer "F.Cu")
    (at 224.4005 118.271 180)
    (descr "Resistor SMD 0402")
    (tags "resistor SMD 0402")
    (property "Author" "Antmicro")
    (property "Current" "1A")
    (property "License" "Apache-2.0")
    (property "MPN" "ERJ2GE0R00X")
    (property "Manufacturer" "Panasonic")
    (property "Sheetfile" "config-spi.kicad_sch")
    (property "Sheetname" "Config SPI flash")
    (property "Tolerance" "")
    (property "Val" "0R")
    (property "ki_description" "0R resistor in 0402 package with unspecified tolerance")
    (attr smd)
    (fp_text reference "R27" (at 1.1805 -1.169 180) (layer "F.SilkS")
        (effects (font (size 0.7 0.7) (thickness 0.15)) (justify left bottom))
    )
    (fp_text value "R_0R_0402" (at 0 1.4 180) (layer "F.Fab") hide
        (effects (font (size 0.7 0.7) (thickness 0.15)) (justify left bottom))
    )
    (fp_text user "${REFERENCE}" (at -0.95 3.168 180) (layer "F.Fab") hide
        (effects (font (size 0.7 0.7) (thickness 0.15)) (justify left bottom))
    )
    (fp_text user "Author: Antmicro" (at -0.95 4.169 180) (layer "F.Fab") hide
        (effects (font (size 0.7 0.7) (thickness 0.15)) (justify left bottom))
    )
    (fp_text user "License: Apache-2.0" (at -0.95 5.169 180) (layer "F.Fab") hide
        (effects (font (size 0.7 0.7) (thickness 0.15)) (justify left bottom))
    )
    (fp_rect (start -0.93 -0.47) (end 0.93 0.47)
      (stroke (width 0.05) (type solid)) (fill none) (layer "F.CrtYd"))
    (fp_rect (start -0.5 -0.25) (end 0.5 0.25)
      (stroke (width 0.15) (type solid)) (fill none) (layer "F.Fab"))
    (pad "1" smd roundrect (at -0.485 0 180) (size 0.59 0.64) (layers "F.Cu" "F.Paste" "F.Mask") (roundrect_rratio 0.25)
      (net 600 "Net-(U3-~{WP}{slash}IO2)") (pintype "passive"))
    (pad "2" smd roundrect (at 0.485 0 180) (size 0.59 0.64) (layers "F.Cu" "F.Paste" "F.Mask") (roundrect_rratio 0.25)
      (net 21 "QSPI_DQ2") (pintype "passive"))
  )
	(footprint "data-center-rdimm-ddr4-tester-footprints:R_0402_1005Metric" (layer "F.Cu")
    (at 220.787 112.867 -90)
    (descr "Resistor SMD 0402")
    (tags "resistor SMD 0402")
    (property "Author" "Antmicro")
    (property "DNP" "DNP")
    (property "License" "Apache-2.0")
    (property "MPN" "CR0402-FX-1000GLF")
    (property "Manufacturer" "Bourns")
    (property "Sheetfile" "config-spi.kicad_sch")
    (property "Sheetname" "Config SPI flash")
    (property "Tolerance" "1%")
    (property "Val" "100R")
    (property "dnp" "")
    (property "exclude_from_bom" "")
    (property "ki_description" "100R resistor in 0402 package with 1% tolerance")
    (attr exclude_from_pos_files exclude_from_bom)
    (fp_text reference "R36" (at -0.667 -0.363 -90) (layer "F.SilkS")
        (effects (font (size 0.7 0.7) (thickness 0.15)) (justify left bottom))
    )
    (fp_text value "R_100R_0402" (at 0 1.4 -90) (layer "F.Fab") hide
        (effects (font (size 0.7 0.7) (thickness 0.15)) (justify left bottom))
    )
    (fp_text user "Author: Antmicro" (at -0.95 4.169 -90) (layer "F.Fab") hide
        (effects (font (size 0.7 0.7) (thickness 0.15)) (justify left bottom))
    )
    (fp_text user "License: Apache-2.0" (at -0.95 5.169 -90) (layer "F.Fab") hide
        (effects (font (size 0.7 0.7) (thickness 0.15)) (justify left bottom))
    )
    (fp_text user "${REFERENCE}" (at -0.95 3.168 -90) (layer "F.Fab") hide
        (effects (font (size 0.7 0.7) (thickness 0.15)) (justify left bottom))
    )
    (fp_rect (start -0.93 -0.47) (end 0.93 0.47)
      (stroke (width 0.05) (type solid)) (fill none) (layer "F.CrtYd"))
    (fp_rect (start -0.5 -0.25) (end 0.5 0.25)
      (stroke (width 0.15) (type solid)) (fill none) (layer "F.Fab"))
    (pad "1" smd roundrect (at -0.485 0 270) (size 0.59 0.64) (layers "F.Cu" "F.Paste" "F.Mask") (roundrect_rratio 0.25)
      (net 79 "PUDC_B") (pintype "passive"))
    (pad "2" smd roundrect (at 0.485 0 270) (size 0.59 0.64) (layers "F.Cu" "F.Paste" "F.Mask") (roundrect_rratio 0.25)
      (net 9 "GND") (pintype "passive"))
  )
	(footprint "data-center-rdimm-ddr4-tester-footprints:R_0402_1005Metric" (layer "F.Cu")
    (at 235.767 119.541)
    (descr "Resistor SMD 0402")
    (tags "resistor SMD 0402")
    (property "Author" "Antmicro")
    (property "Current" "1A")
    (property "License" "Apache-2.0")
    (property "MPN" "ERJ2GE0R00X")
    (property "Manufacturer" "Panasonic")
    (property "Sheetfile" "config-spi.kicad_sch")
    (property "Sheetname" "Config SPI flash")
    (property "Tolerance" "")
    (property "Val" "0R")
    (property "ki_description" "0R resistor in 0402 package with unspecified tolerance")
    (attr smd)
    (fp_text reference "R59" (at -1.027 -4.361) (layer "F.SilkS")
        (effects (font (size 0.7 0.7) (thickness 0.15)) (justify left bottom))
    )
    (fp_text value "R_0R_0402" (at 0 1.4) (layer "F.Fab") hide
        (effects (font (size 0.7 0.7) (thickness 0.15)) (justify left bottom))
    )
    (fp_text user "Author: Antmicro" (at -0.95 4.169) (layer "F.Fab") hide
        (effects (font (size 0.7 0.7) (thickness 0.15)) (justify left bottom))
    )
    (fp_text user "License: Apache-2.0" (at -0.95 5.169) (layer "F.Fab") hide
        (effects (font (size 0.7 0.7) (thickness 0.15)) (justify left bottom))
    )
    (fp_text user "${REFERENCE}" (at -0.95 3.168) (layer "F.Fab") hide
        (effects (font (size 0.7 0.7) (thickness 0.15)) (justify left bottom))
    )
    (fp_rect (start -0.93 -0.47) (end 0.93 0.47)
      (stroke (width 0.05) (type solid)) (fill none) (layer "F.CrtYd"))
    (fp_rect (start -0.5 -0.25) (end 0.5 0.25)
      (stroke (width 0.15) (type solid)) (fill none) (layer "F.Fab"))
    (pad "1" smd roundrect (at -0.485 0) (size 0.59 0.64) (layers "F.Cu" "F.Paste" "F.Mask") (roundrect_rratio 0.25)
      (net 650 "Net-(U3-SI{slash}IO0)") (pintype "passive"))
    (pad "2" smd roundrect (at 0.485 0) (size 0.59 0.64) (layers "F.Cu" "F.Paste" "F.Mask") (roundrect_rratio 0.25)
      (net 19 "QSPI_DQ0") (pintype "passive"))
  )
	(footprint "data-center-rdimm-ddr4-tester-footprints:R_0402_1005Metric" (layer "F.Cu")
    (at 224.4005 117.001 180)
    (descr "Resistor SMD 0402")
    (tags "resistor SMD 0402")
    (property "Author" "Antmicro")
    (property "Current" "1A")
    (property "License" "Apache-2.0")
    (property "MPN" "ERJ2GE0R00X")
    (property "Manufacturer" "Panasonic")
    (property "Sheetfile" "config-spi.kicad_sch")
    (property "Sheetname" "Config SPI flash")
    (property "Tolerance" "")
    (property "Val" "0R")
    (property "ki_description" "0R resistor in 0402 package with unspecified tolerance")
    (attr smd)
    (fp_text reference "R60" (at 3.0105 -0.399 180) (layer "F.SilkS")
        (effects (font (size 0.7 0.7) (thickness 0.15)) (justify left bottom))
    )
    (fp_text value "R_0R_0402" (at 0 1.4 180) (layer "F.Fab") hide
        (effects (font (size 0.7 0.7) (thickness 0.15)) (justify left bottom))
    )
    (fp_text user "${REFERENCE}" (at -0.95 3.168 180) (layer "F.Fab") hide
        (effects (font (size 0.7 0.7) (thickness 0.15)) (justify left bottom))
    )
    (fp_text user "License: Apache-2.0" (at -0.95 5.169 180) (layer "F.Fab") hide
        (effects (font (size 0.7 0.7) (thickness 0.15)) (justify left bottom))
    )
    (fp_text user "Author: Antmicro" (at -0.95 4.169 180) (layer "F.Fab") hide
        (effects (font (size 0.7 0.7) (thickness 0.15)) (justify left bottom))
    )
    (fp_rect (start -0.93 -0.47) (end 0.93 0.47)
      (stroke (width 0.05) (type solid)) (fill none) (layer "F.CrtYd"))
    (fp_rect (start -0.5 -0.25) (end 0.5 0.25)
      (stroke (width 0.15) (type solid)) (fill none) (layer "F.Fab"))
    (pad "1" smd roundrect (at -0.485 0 180) (size 0.59 0.64) (layers "F.Cu" "F.Paste" "F.Mask") (roundrect_rratio 0.25)
      (net 651 "Net-(U3-SO{slash}IO1)") (pintype "passive"))
    (pad "2" smd roundrect (at 0.485 0 180) (size 0.59 0.64) (layers "F.Cu" "F.Paste" "F.Mask") (roundrect_rratio 0.25)
      (net 20 "QSPI_DQ1") (pintype "passive"))
  )
	(footprint "data-center-rdimm-ddr4-tester-footprints:R_0402_1005Metric" (layer "F.Cu")
    (at 235.767 118.271)
    (descr "Resistor SMD 0402")
    (tags "resistor SMD 0402")
    (property "Author" "Antmicro")
    (property "Current" "1A")
    (property "License" "Apache-2.0")
    (property "MPN" "ERJ2GE0R00X")
    (property "Manufacturer" "Panasonic")
    (property "Sheetfile" "config-spi.kicad_sch")
    (property "Sheetname" "Config SPI flash")
    (property "Tolerance" "")
    (property "Val" "0R")
    (property "ki_description" "0R resistor in 0402 package with unspecified tolerance")
    (attr smd)
    (fp_text reference "R24" (at -1.027 -4.011) (layer "F.SilkS")
        (effects (font (size 0.7 0.7) (thickness 0.15)) (justify left bottom))
    )
    (fp_text value "R_0R_0402" (at 0 1.4) (layer "F.Fab") hide
        (effects (font (size 0.7 0.7) (thickness 0.15)) (justify left bottom))
    )
    (fp_text user "License: Apache-2.0" (at -0.95 5.169) (layer "F.Fab") hide
        (effects (font (size 0.7 0.7) (thickness 0.15)) (justify left bottom))
    )
    (fp_text user "Author: Antmicro" (at -0.95 4.169) (layer "F.Fab") hide
        (effects (font (size 0.7 0.7) (thickness 0.15)) (justify left bottom))
    )
    (fp_text user "${REFERENCE}" (at -0.95 3.168) (layer "F.Fab") hide
        (effects (font (size 0.7 0.7) (thickness 0.15)) (justify left bottom))
    )
    (fp_rect (start -0.93 -0.47) (end 0.93 0.47)
      (stroke (width 0.05) (type solid)) (fill none) (layer "F.CrtYd"))
    (fp_rect (start -0.5 -0.25) (end 0.5 0.25)
      (stroke (width 0.15) (type solid)) (fill none) (layer "F.Fab"))
    (pad "1" smd roundrect (at -0.485 0) (size 0.59 0.64) (layers "F.Cu" "F.Paste" "F.Mask") (roundrect_rratio 0.25)
      (net 597 "Net-(U3-SCK)") (pintype "passive"))
    (pad "2" smd roundrect (at 0.485 0) (size 0.59 0.64) (layers "F.Cu" "F.Paste" "F.Mask") (roundrect_rratio 0.25)
      (net 96 "CCLK") (pintype "passive"))
  )
	(footprint "data-center-rdimm-ddr4-tester-footprints:C_0603_1608Metric" (layer "F.Cu")
    (at 139.5 98.25 180)
    (descr "Capacitor SMD 0603")
    (tags "capacitor 0603")
    (property "Author" "Antmicro")
    (property "Dielectric" "")
    (property "License" "Apache-2.0")
    (property "MPN" "06031C103JAT2A")
    (property "Manufacturer" "AVX")
    (property "Sheetfile" "supply.kicad_sch")
    (property "Sheetname" "Supply")
    (property "Val" "10n")
    (property "Voltage" "")
    (property "ki_description" " ")
    (attr smd)
    (fp_text reference "C100" (at -1.01 -0.34 180) (layer "F.SilkS")
        (effects (font (size 0.7 0.7) (thickness 0.15)) (justify left bottom))
    )
    (fp_text value "C_10n_0603" (at 0 1.6 180) (layer "F.Fab") hide
        (effects (font (size 0.7 0.7) (thickness 0.15)) (justify left bottom))
    )
    (fp_text user "Author: Antmicro" (at -1.682 4.894 180) (layer "F.Fab") hide
        (effects (font (size 0.7 0.7) (thickness 0.15)) (justify left bottom))
    )
    (fp_text user "${REFERENCE}" (at -1.682 3.895 180) (layer "F.Fab") hide
        (effects (font (size 0.7 0.7) (thickness 0.15)) (justify left bottom))
    )
    (fp_text user "License: Apache-2.0" (at -1.682 5.895 180) (layer "F.Fab") hide
        (effects (font (size 0.7 0.7) (thickness 0.15)) (justify left bottom))
    )
    (fp_line (start -0.3 -0.3) (end 0.3 -0.3)
      (stroke (width 0.15) (type solid)) (layer "F.SilkS"))
    (fp_line (start -0.3 0.3) (end 0.3 0.3)
      (stroke (width 0.15) (type solid)) (layer "F.SilkS"))
    (fp_rect (start -1.24 -0.7) (end 1.24 0.7)
      (stroke (width 0.05) (type solid)) (fill none) (layer "F.CrtYd"))
    (fp_rect (start -0.8 -0.4) (end 0.8 0.4)
      (stroke (width 0.15) (type solid)) (fill none) (layer "F.Fab"))
    (pad "1" smd roundrect (at -0.7 0 180) (size 0.6 0.8) (layers "F.Cu" "F.Paste" "F.Mask") (roundrect_rratio 0.2)
      (net 4 "Net-(U10-TADJ)") (pintype "passive"))
    (pad "2" smd roundrect (at 0.7 0 180) (size 0.6 0.8) (layers "F.Cu" "F.Paste" "F.Mask") (roundrect_rratio 0.2)
      (net 9 "GND") (pintype "passive"))
  )
	(footprint "data-center-rdimm-ddr4-tester-footprints:C_0402_1005Metric" (layer "F.Cu")
    (at 136.786328 93.010008)
    (descr "Capacitor SMD 0402")
    (tags "capacitor SMD 0402")
    (property "Author" "Antmicro")
    (property "Dielectric" "X5R")
    (property "License" "Apache-2.0")
    (property "MPN" "GRM155R61H104KE14D")
    (property "Manufacturer" "Murata")
    (property "Sheetfile" "supply.kicad_sch")
    (property "Sheetname" "Supply")
    (property "Val" "100n")
    (property "Voltage" "50V")
    (property "ki_description" " ")
    (attr smd)
    (fp_text reference "C101" (at -1.136328 -0.480008) (layer "F.SilkS")
        (effects (font (size 0.7 0.7) (thickness 0.15)) (justify left bottom))
    )
    (fp_text value "C_100n_0402" (at 0 1.4) (layer "F.Fab") hide
        (effects (font (size 0.7 0.7) (thickness 0.15)) (justify left bottom))
    )
    (fp_text user "${REFERENCE}" (at -0.932 3.168) (layer "F.Fab") hide
        (effects (font (size 0.7 0.7) (thickness 0.15)) (justify left bottom))
    )
    (fp_text user "License: Apache-2.0" (at -0.932 5.17) (layer "F.Fab") hide
        (effects (font (size 0.7 0.7) (thickness 0.15)) (justify left bottom))
    )
    (fp_text user "Author: Antmicro" (at -0.932 4.17) (layer "F.Fab") hide
        (effects (font (size 0.7 0.7) (thickness 0.15)) (justify left bottom))
    )
    (fp_rect (start -0.94 -0.47) (end 0.94 0.47)
      (stroke (width 0.05) (type solid)) (fill none) (layer "F.CrtYd"))
    (fp_rect (start -0.499 -0.249) (end 0.499 0.249)
      (stroke (width 0.15) (type solid)) (fill none) (layer "F.Fab"))
    (pad "1" smd roundrect (at -0.484 0) (size 0.59 0.64) (layers "F.Cu" "F.Paste" "F.Mask") (roundrect_rratio 0.25)
      (net 307 "5V0_SYS") (pintype "passive"))
    (pad "2" smd roundrect (at 0.484 0) (size 0.59 0.64) (layers "F.Cu" "F.Paste" "F.Mask") (roundrect_rratio 0.25)
      (net 9 "GND") (pintype "passive"))
  )
)
